(kicad_pcb
	(version 20221018)
	(generator pcbnew)
	(general
    (thickness 1.518)
  )
	(paper "A4")
	(title_block
    (title "Kria K26 Devboard")
    (date "2024-03-26")
    (rev "1.2.5")
    (comment 1 "www.antmicro.com")
    (comment 2 "Antmicro Ltd.")
		(comment 9 "footprint 368 of 660 (U17), pads 82-101 of 101")
	)
	(layers
    (0 "F.Cu" mixed)
    (1 "In1.Cu" power)
    (2 "In2.Cu" mixed)
    (3 "In3.Cu" power)
    (4 "In4.Cu" mixed)
    (5 "In5.Cu" power)
    (6 "In6.Cu" mixed)
    (31 "B.Cu" power)
    (32 "B.Adhes" user "B.Adhesive")
    (33 "F.Adhes" user "F.Adhesive")
    (34 "B.Paste" user)
    (35 "F.Paste" user)
    (36 "B.SilkS" user "B.Silkscreen")
    (37 "F.SilkS" user "F.Silkscreen")
    (38 "B.Mask" user)
    (39 "F.Mask" user)
    (40 "Dwgs.User" user "User.Drawings")
    (41 "Cmts.User" user "User.Comments")
    (42 "Eco1.User" user "User.Eco1")
    (43 "Eco2.User" user "User.Eco2")
    (44 "Edge.Cuts" user)
    (45 "Margin" user)
    (46 "B.CrtYd" user "B.Courtyard")
    (47 "F.CrtYd" user "F.Courtyard")
    (48 "B.Fab" user)
    (49 "F.Fab" user)
  )
	(footprint "kria-k26-devboard-footprints:VQFN-100-1EP_12x12x0.85mm_P0.4mm"
    (layer "F.Cu")
    (at 122.118942 84.534861 180)
    (property "Author" "Antmicro")
    (property "License" "Apache-2.0")
    (property "MPN" "USB7016/KDX")
    (property "Manufacturer" "Microchip Technology")
    (property "Sheetfile" "usb.kicad_sch")
    (property "Sheetname" "USB")
    (property "ki_description" "USB hub controller")
    (property "ki_keywords" "SMT, INTERFACE, CONTROLLER, IC, USB, HUB")
    (attr smd)
    (fp_text reference "U17" (at 6.678942 4.194861 270) (layer "F.SilkS")
        (effects (font (size 0.7 0.7) (thickness 0.15)) (justify left bottom))
    )
    (fp_text value "USB7016_KDX" (at 0 7.6 180) (layer "F.Fab")
        (effects (font (size 0.7 0.7) (thickness 0.15)) (justify left bottom))
    )
    (pad "82" smd roundrect (at 2.398 -5.789 180) (size 0.204 1.011199) (layers "F.Cu" "F.Paste" "F.Mask") (roundrect_rratio 0.25)
      (net 77 "/USB/USB4_N") (pinfunction "USB2DN_DM4/PRT_DIS_M4") (pintype "bidirectional"))
    (pad "83" smd roundrect (at 1.999 -5.789 180) (size 0.204 1.011199) (layers "F.Cu" "F.Paste" "F.Mask") (roundrect_rratio 0.25)
      (net 76 "/USB/USB4_TX_P") (pinfunction "USB3DN_TXDP4") (pintype "bidirectional"))
    (pad "84" smd roundrect (at 1.598 -5.789 180) (size 0.204 1.011199) (layers "F.Cu" "F.Paste" "F.Mask") (roundrect_rratio 0.25)
      (net 75 "/USB/USB4_TX_N") (pinfunction "USB3DN_TXDM4") (pintype "bidirectional"))
    (pad "85" smd roundrect (at 1.199 -5.789 180) (size 0.204 1.011199) (layers "F.Cu" "F.Paste" "F.Mask") (roundrect_rratio 0.25)
      (net 18 "PS_1V2") (pinfunction "VCORE") (pintype "passive"))
    (pad "86" smd roundrect (at 0.8 -5.789 180) (size 0.204 1.011199) (layers "F.Cu" "F.Paste" "F.Mask") (roundrect_rratio 0.25)
      (net 74 "/USB/USB4_RX_P") (pinfunction "USB3DN_RXDP4") (pintype "bidirectional"))
    (pad "87" smd roundrect (at 0.399 -5.789 180) (size 0.204 1.011199) (layers "F.Cu" "F.Paste" "F.Mask") (roundrect_rratio 0.25)
      (net 73 "/USB/USB4_RX_N") (pinfunction "USB3DN_RXDM4") (pintype "bidirectional"))
    (pad "88" smd roundrect (at 0 -5.789 180) (size 0.204 1.011199) (layers "F.Cu" "F.Paste" "F.Mask") (roundrect_rratio 0.25)
      (net 15 "PS_3V3") (pinfunction "VDD33") (pintype "passive"))
    (pad "89" smd roundrect (at -0.401 -5.789 180) (size 0.204 1.011199) (layers "F.Cu" "F.Paste" "F.Mask") (roundrect_rratio 0.25)
      (net 55 "/USB/USB2_PHY_P") (pinfunction "USB2UP_DP") (pintype "bidirectional"))
    (pad "90" smd roundrect (at -0.802 -5.789 180) (size 0.204 1.011199) (layers "F.Cu" "F.Paste" "F.Mask") (roundrect_rratio 0.25)
      (net 54 "/USB/USB2_PHY_N") (pinfunction "USB2UP_DM") (pintype "bidirectional"))
    (pad "91" smd roundrect (at -1.2 -5.789 180) (size 0.204 1.011199) (layers "F.Cu" "F.Paste" "F.Mask") (roundrect_rratio 0.25)
      (net 52 "/USB/GTR_DP2_C2M_C_P") (pinfunction "USB3UP_TXDP") (pintype "bidirectional"))
    (pad "92" smd roundrect (at -1.601 -5.789 180) (size 0.204 1.011199) (layers "F.Cu" "F.Paste" "F.Mask") (roundrect_rratio 0.25)
      (net 53 "/USB/GTR_DP2_C2M_C_N") (pinfunction "USB3UP_TXDM") (pintype "bidirectional"))
    (pad "93" smd roundrect (at -2 -5.789 180) (size 0.204 1.011199) (layers "F.Cu" "F.Paste" "F.Mask") (roundrect_rratio 0.25)
      (net 18 "PS_1V2") (pinfunction "VCORE") (pintype "passive"))
    (pad "94" smd roundrect (at -2.4 -5.789 180) (size 0.204 1.011199) (layers "F.Cu" "F.Paste" "F.Mask") (roundrect_rratio 0.25)
      (net 320 "/USB/GTR_DP2_M2C_C_P") (pinfunction "USB3UP_RXDP") (pintype "bidirectional"))
    (pad "95" smd roundrect (at -2.801 -5.789 180) (size 0.204 1.011199) (layers "F.Cu" "F.Paste" "F.Mask") (roundrect_rratio 0.25)
      (net 321 "/USB/GTR_DP2_M2C_C_N") (pinfunction "USB3UP_RXDM") (pintype "bidirectional"))
    (pad "96" smd roundrect (at -3.201 -5.789 180) (size 0.204 1.011199) (layers "F.Cu" "F.Paste" "F.Mask") (roundrect_rratio 0.25)
      (net 722 "unconnected-(U17-ATEST-Pad96)") (pinfunction "ATEST") (pintype "no_connect"))
    (pad "97" smd roundrect (at -3.601 -5.789 180) (size 0.204 1.011199) (layers "F.Cu" "F.Paste" "F.Mask") (roundrect_rratio 0.25)
      (net 723 "unconnected-(U17-XTALO-Pad97)") (pinfunction "XTALO") (pintype "output+no_connect"))
    (pad "98" smd roundrect (at -4 -5.789 180) (size 0.204 1.011199) (layers "F.Cu" "F.Paste" "F.Mask") (roundrect_rratio 0.25)
      (net 294 "/USB/CLK_IN") (pinfunction "XTALI/CLK_IN") (pintype "input"))
    (pad "99" smd roundrect (at -4.401 -5.789 180) (size 0.204 1.011199) (layers "F.Cu" "F.Paste" "F.Mask") (roundrect_rratio 0.25)
      (net 15 "PS_3V3") (pinfunction "VDD33") (pintype "passive"))
    (pad "100" smd roundrect (at -4.8 -5.789 180) (size 0.204 1.011199) (layers "F.Cu" "F.Paste" "F.Mask") (roundrect_rratio 0.25)
      (net 655 "Net-(U17-RBIAS)") (pinfunction "RBIAS") (pintype "input"))
    (pad "101" smd roundrect (at 0 0 180) (size 8.1026 8.1026) (layers "F.Cu" "F.Mask") (roundrect_rratio 0.05)
      (net 1 "GND") (pinfunction "VSS") (pintype "power_in"))
  )
)
